(kicad_pcb
	(version 20241229)
	(generator "pcbnew")
	(generator_version "9.0")
	(general
		(thickness 1.61)
		(legacy_teardrops no)
	)
	(paper "A3")
	(title_block
		(title "SO-DIMM DDR5 Tester")
		(date "2025-11-26")
		(rev "1.3.0")
		(comment 9 "footprints 473-478 of 627")
	)
	(layers
		(0 "F.Cu" signal)
		(4 "In1.Cu" power)
		(6 "In2.Cu" mixed)
		(8 "In3.Cu" power)
		(10 "In4.Cu" mixed)
		(12 "In5.Cu" power)
		(14 "In6.Cu" mixed)
		(16 "In7.Cu" power)
		(18 "In8.Cu" power)
		(20 "In9.Cu" mixed)
		(22 "In10.Cu" power)
		(2 "B.Cu" signal)
		(9 "F.Adhes" user "F.Adhesive")
		(11 "B.Adhes" user "B.Adhesive")
		(13 "F.Paste" user)
		(15 "B.Paste" user)
		(5 "F.SilkS" user "F.Silkscreen")
		(7 "B.SilkS" user "B.Silkscreen")
		(1 "F.Mask" user)
		(3 "B.Mask" user)
		(17 "Dwgs.User" user "User.Drawings")
		(19 "Cmts.User" user "User.Comments")
		(21 "Eco1.User" user "User.Eco1")
		(23 "Eco2.User" user "User.Eco2")
		(25 "Edge.Cuts" user)
		(27 "Margin" user)
		(31 "F.CrtYd" user "F.Courtyard")
		(29 "B.CrtYd" user "B.Courtyard")
		(35 "F.Fab" user)
		(33 "B.Fab" user)
	)
	(footprint "antmicro-footprints:C_0603_1608Metric"
		(layer "B.Cu")
		(at 114.275501 176.726 -90)
		(descr "Capacitor SMD 0603")
		(tags "capacitor 0603")
		(property "Reference" "C1"
			(at -1.42757 1.000252 90)
			(layer "B.SilkS")
			(hide yes)
			(effects
				(font
					(size 0.7 0.7)
					(thickness 0.15)
				)
				(justify left bottom mirror)
			)
		)
		(property "Value" "C_47u_0603"
			(at -1.42757 -1.770288 90)
			(layer "B.Fab")
			(effects
				(font
					(size 0.7 0.7)
					(thickness 0.15)
				)
				(justify left bottom mirror)
			)
		)
		(property "Datasheet" "https://www.murata.com/products/productdetail?partno=GRM188R60J476ME15%23"
			(at 0 0 270)
			(layer "F.Fab")
			(hide yes)
			(effects
				(font
					(size 1.27 1.27)
					(thickness 0.15)
				)
			)
		)
		(property "Author" "Antmicro"
			(at -62.450499 291.001501 0)
			(layer "B.Fab")
			(hide yes)
			(effects
				(font
					(size 1 1)
					(thickness 0.15)
				)
				(justify mirror)
			)
		)
		(property "Dielectric" ""
			(at -62.450499 291.001501 0)
			(layer "B.Fab")
			(hide yes)
			(effects
				(font
					(size 1 1)
					(thickness 0.15)
				)
				(justify mirror)
			)
		)
		(property "License" "Apache-2.0"
			(at -62.450499 291.001501 0)
			(layer "B.Fab")
			(hide yes)
			(effects
				(font
					(size 1 1)
					(thickness 0.15)
				)
				(justify mirror)
			)
		)
		(property "MPN" "GRM188R60J476ME15D"
			(at -62.450499 291.001501 0)
			(layer "B.Fab")
			(hide yes)
			(effects
				(font
					(size 1 1)
					(thickness 0.15)
				)
				(justify mirror)
			)
		)
		(property "Manufacturer" "Murata"
			(at -62.450499 291.001501 0)
			(layer "B.Fab")
			(hide yes)
			(effects
				(font
					(size 1 1)
					(thickness 0.15)
				)
				(justify mirror)
			)
		)
		(property "Val" "47u"
			(at -62.450499 291.001501 0)
			(layer "B.Fab")
			(hide yes)
			(effects
				(font
					(size 1 1)
					(thickness 0.15)
				)
				(justify mirror)
			)
		)
		(property "Voltage" ""
			(at -62.450499 291.001501 0)
			(layer "B.Fab")
			(hide yes)
			(effects
				(font
					(size 1 1)
					(thickness 0.15)
				)
				(justify mirror)
			)
		)
		(sheetname "/HyperRAM + QSPI Flash/")
		(sheetfile "hyperram-flash.kicad_sch")
		(attr smd)
		(fp_line
			(start -0.3 0.3)
			(end 0.3 0.3)
			(stroke
				(width 0.15)
				(type solid)
			)
			(layer "B.SilkS")
		)
		(fp_line
			(start -0.3 -0.3)
			(end 0.3 -0.3)
			(stroke
				(width 0.15)
				(type solid)
			)
			(layer "B.SilkS")
		)
		(fp_rect
			(start -1.24 0.7)
			(end 1.24 -0.7)
			(stroke
				(width 0.05)
				(type solid)
			)
			(fill no)
			(layer "B.CrtYd")
		)
		(fp_rect
			(start -0.8 0.4)
			(end 0.8 -0.4)
			(stroke
				(width 0.15)
				(type solid)
			)
			(fill no)
			(layer "B.Fab")
		)
		(pad "1" smd roundrect
			(at -0.7 0 270)
			(size 0.6 0.8)
			(layers "B.Cu" "B.Mask" "B.Paste")
			(roundrect_rratio 0.2)
			(net 200 "+3V3")
			(pintype "passive")
		)
		(pad "2" smd roundrect
			(at 0.7 0 270)
			(size 0.6 0.8)
			(layers "B.Cu" "B.Mask" "B.Paste")
			(roundrect_rratio 0.2)
			(net 1 "GND")
			(pintype "passive")
		)
	)
	(footprint "antmicro-footprints:C_0402_1005Metric"
		(layer "B.Cu")
		(at 140.875001 182.3005 180)
		(descr "Capacitor SMD 0402 (1005 Metric), square (rectangular) end terminal, IPC_7351 nominal, (Body size source: IPC-SM-782 page 76, https://www.pcb-3d.com/wordpress/wp-content/uploads/ipc-sm-782a_amendment_1_and_2.pdf)")
		(tags "capacitor 0402")
		(property "Reference" "C32"
			(at 0 1.17 0)
			(layer "B.SilkS")
			(hide yes)
			(effects
				(font
					(size 0.7 0.7)
					(thickness 0.15)
				)
				(justify left bottom mirror)
			)
		)
		(property "Value" "C_100n_0402"
			(at 0 -1.169 0)
			(layer "B.Fab")
			(effects
				(font
					(size 0.7 0.7)
					(thickness 0.15)
				)
				(justify left bottom mirror)
			)
		)
		(property "Datasheet" "https://www.murata.com/products/productdetail?partno=GRM155R61H104KE14%23"
			(at 0 0 180)
			(layer "F.Fab")
			(hide yes)
			(effects
				(font
					(size 1.27 1.27)
					(thickness 0.15)
				)
			)
		)
		(property "Author" "Antmicro"
			(at 281.750002 364.601 0)
			(layer "B.Fab")
			(hide yes)
			(effects
				(font
					(size 1 1)
					(thickness 0.15)
				)
				(justify mirror)
			)
		)
		(property "Dielectric" "X5R"
			(at 281.750002 364.601 0)
			(layer "B.Fab")
			(hide yes)
			(effects
				(font
					(size 1 1)
					(thickness 0.15)
				)
				(justify mirror)
			)
		)
		(property "License" "Apache-2.0"
			(at 281.750002 364.601 0)
			(layer "B.Fab")
			(hide yes)
			(effects
				(font
					(size 1 1)
					(thickness 0.15)
				)
				(justify mirror)
			)
		)
		(property "MPN" "GRM155R61H104KE14D"
			(at 281.750002 364.601 0)
			(layer "B.Fab")
			(hide yes)
			(effects
				(font
					(size 1 1)
					(thickness 0.15)
				)
				(justify mirror)
			)
		)
		(property "Manufacturer" "Murata"
			(at 281.750002 364.601 0)
			(layer "B.Fab")
			(hide yes)
			(effects
				(font
					(size 1 1)
					(thickness 0.15)
				)
				(justify mirror)
			)
		)
		(property "Val" "100n"
			(at 281.750002 364.601 0)
			(layer "B.Fab")
			(hide yes)
			(effects
				(font
					(size 1 1)
					(thickness 0.15)
				)
				(justify mirror)
			)
		)
		(property "Voltage" "50V"
			(at 281.750002 364.601 0)
			(layer "B.Fab")
			(hide yes)
			(effects
				(font
					(size 1 1)
					(thickness 0.15)
				)
				(justify mirror)
			)
		)
		(sheetname "/FPGA power/")
		(sheetfile "fpga-power.kicad_sch")
		(attr smd)
		(fp_rect
			(start -0.9656 0.4572)
			(end 0.9652 -0.4828)
			(stroke
				(width 0.05)
				(type solid)
			)
			(fill no)
			(layer "B.CrtYd")
		)
		(fp_line
			(start 0.498 0.25)
			(end 0.498 -0.248)
			(stroke
				(width 0.15)
				(type solid)
			)
			(layer "B.Fab")
		)
		(fp_line
			(start 0.498 -0.248)
			(end -0.5 -0.248)
			(stroke
				(width 0.15)
				(type solid)
			)
			(layer "B.Fab")
		)
		(fp_line
			(start -0.5 0.25)
			(end 0.498 0.25)
			(stroke
				(width 0.15)
				(type solid)
			)
			(layer "B.Fab")
		)
		(fp_line
			(start -0.5 -0.248)
			(end -0.5 0.25)
			(stroke
				(width 0.15)
				(type solid)
			)
			(layer "B.Fab")
		)
		(pad "1" smd roundrect
			(at -0.5 0 90)
			(size 0.6 0.6)
			(layers "B.Cu" "B.Mask" "B.Paste")
			(roundrect_rratio 0.25)
			(net 1 "GND")
			(pintype "passive")
		)
		(pad "2" smd roundrect
			(at 0.498 0 180)
			(size 0.6 0.6)
			(layers "B.Cu" "B.Mask" "B.Paste")
			(roundrect_rratio 0.25)
			(net 200 "+3V3")
			(pintype "passive")
		)
	)
	(footprint "antmicro-footprints:R_0402_1005Metric"
		(layer "B.Cu")
		(at 140.67 142.4 -90)
		(descr "Resistor SMD 0402")
		(tags "resistor SMD 0402")
		(property "Reference" "R34"
			(at -3.044968 -0.354606 90)
			(layer "B.SilkS")
			(effects
				(font
					(size 0.7 0.7)
					(thickness 0.15)
				)
				(justify left bottom mirror)
			)
		)
		(property "Value" "R_0R_0402"
			(at -1.011843 -1.772047 90)
			(layer "B.Fab")
			(effects
				(font
					(size 0.7 0.7)
					(thickness 0.15)
				)
				(justify left bottom mirror)
			)
		)
		(property "Datasheet" "https://industrial.panasonic.com/cdbs/www-data/pdf/RDA0000/AOA0000C301.pdf"
			(at 0 0 270)
			(layer "F.Fab")
			(hide yes)
			(effects
				(font
					(size 1.27 1.27)
					(thickness 0.15)
				)
			)
		)
		(property "Author" "Antmicro"
			(at -1.73 283.07 0)
			(layer "B.Fab")
			(hide yes)
			(effects
				(font
					(size 1 1)
					(thickness 0.15)
				)
				(justify mirror)
			)
		)
		(property "Current" "1A"
			(at -1.73 283.07 0)
			(layer "B.Fab")
			(hide yes)
			(effects
				(font
					(size 1 1)
					(thickness 0.15)
				)
				(justify mirror)
			)
		)
		(property "License" "Apache-2.0"
			(at -1.73 283.07 0)
			(layer "B.Fab")
			(hide yes)
			(effects
				(font
					(size 1 1)
					(thickness 0.15)
				)
				(justify mirror)
			)
		)
		(property "MPN" "ERJ2GE0R00X"
			(at -1.73 283.07 0)
			(layer "B.Fab")
			(hide yes)
			(effects
				(font
					(size 1 1)
					(thickness 0.15)
				)
				(justify mirror)
			)
		)
		(property "Manufacturer" "Panasonic"
			(at -1.73 283.07 0)
			(layer "B.Fab")
			(hide yes)
			(effects
				(font
					(size 1 1)
					(thickness 0.15)
				)
				(justify mirror)
			)
		)
		(property "Tolerance" ""
			(at -1.73 283.07 0)
			(layer "B.Fab")
			(hide yes)
			(effects
				(font
					(size 1 1)
					(thickness 0.15)
				)
				(justify mirror)
			)
		)
		(property "Val" "0R"
			(at -1.73 283.07 0)
			(layer "B.Fab")
			(hide yes)
			(effects
				(font
					(size 1 1)
					(thickness 0.15)
				)
				(justify mirror)
			)
		)
		(sheetname "/DDR5 SODIMM/")
		(sheetfile "ddr5-sodimm.kicad_sch")
		(attr exclude_from_pos_files exclude_from_bom dnp)
		(fp_rect
			(start -0.93 0.47)
			(end 0.93 -0.47)
			(stroke
				(width 0.05)
				(type solid)
			)
			(fill no)
			(layer "B.CrtYd")
		)
		(fp_rect
			(start -0.5 0.25)
			(end 0.5 -0.25)
			(stroke
				(width 0.15)
				(type solid)
			)
			(fill no)
			(layer "B.Fab")
		)
		(pad "1" smd roundrect
			(at -0.485 0 270)
			(size 0.59 0.64)
			(layers "B.Cu" "B.Mask" "B.Paste")
			(roundrect_rratio 0.25)
			(net 171 "/DDR5 SODIMM/RFU2")
			(pintype "passive")
		)
		(pad "2" smd roundrect
			(at 0.485 0 270)
			(size 0.59 0.64)
			(layers "B.Cu" "B.Mask" "B.Paste")
			(roundrect_rratio 0.25)
			(net 101 "RFU_2")
			(pintype "passive")
		)
	)
	(footprint "antmicro-footprints:R_0402_1005Metric"
		(layer "B.Cu")
		(at 146.875001 173.3025 180)
		(descr "Resistor SMD 0402 (1005 Metric), square (rectangular) end terminal, IPC_7351 nominal, (Body size source: IPC-SM-782 page 76, https://www.pcb-3d.com/wordpress/wp-content/uploads/ipc-sm-782a_amendment_1_and_2.pdf)")
		(tags "resistor 0402")
		(property "Reference" "R20"
			(at 0 1.17 0)
			(layer "B.SilkS")
			(hide yes)
			(effects
				(font
					(size 0.7 0.7)
					(thickness 0.15)
				)
				(justify left bottom mirror)
			)
		)
		(property "Value" "R_0R_0402"
			(at 0 -1.169 0)
			(layer "B.Fab")
			(effects
				(font
					(size 0.7 0.7)
					(thickness 0.15)
				)
				(justify left bottom mirror)
			)
		)
		(property "Datasheet" "https://industrial.panasonic.com/cdbs/www-data/pdf/RDA0000/AOA0000C301.pdf"
			(at 0 0 180)
			(layer "F.Fab")
			(hide yes)
			(effects
				(font
					(size 1.27 1.27)
					(thickness 0.15)
				)
			)
		)
		(property "Author" "Antmicro"
			(at 293.750002 346.605 0)
			(layer "B.Fab")
			(hide yes)
			(effects
				(font
					(size 1 1)
					(thickness 0.15)
				)
				(justify mirror)
			)
		)
		(property "Current" "1A"
			(at 293.750002 346.605 0)
			(layer "B.Fab")
			(hide yes)
			(effects
				(font
					(size 1 1)
					(thickness 0.15)
				)
				(justify mirror)
			)
		)
		(property "License" "Apache-2.0"
			(at 293.750002 346.605 0)
			(layer "B.Fab")
			(hide yes)
			(effects
				(font
					(size 1 1)
					(thickness 0.15)
				)
				(justify mirror)
			)
		)
		(property "MPN" "ERJ2GE0R00X"
			(at 293.750002 346.605 0)
			(layer "B.Fab")
			(hide yes)
			(effects
				(font
					(size 1 1)
					(thickness 0.15)
				)
				(justify mirror)
			)
		)
		(property "Manufacturer" "Panasonic"
			(at 293.750002 346.605 0)
			(layer "B.Fab")
			(hide yes)
			(effects
				(font
					(size 1 1)
					(thickness 0.15)
				)
				(justify mirror)
			)
		)
		(property "Tolerance" ""
			(at 293.750002 346.605 0)
			(layer "B.Fab")
			(hide yes)
			(effects
				(font
					(size 1 1)
					(thickness 0.15)
				)
				(justify mirror)
			)
		)
		(property "Val" "0R"
			(at 293.750002 346.605 0)
			(layer "B.Fab")
			(hide yes)
			(effects
				(font
					(size 1 1)
					(thickness 0.15)
				)
				(justify mirror)
			)
		)
		(sheetname "/FPGA Config/")
		(sheetfile "fpga-config.kicad_sch")
		(attr smd)
		(fp_line
			(start 0.9652 0.46)
			(end 0.9652 -0.45)
			(stroke
				(width 0.05)
				(type solid)
			)
			(layer "B.CrtYd")
		)
		(fp_line
			(start 0.9652 -0.45)
			(end -0.95 -0.45)
			(stroke
				(width 0.05)
				(type solid)
			)
			(layer "B.CrtYd")
		)
		(fp_line
			(start -0.95 0.46)
			(end 0.9652 0.46)
			(stroke
				(width 0.05)
				(type solid)
			)
			(layer "B.CrtYd")
		)
		(fp_line
			(start -0.95 -0.45)
			(end -0.95 0.46)
			(stroke
				(width 0.05)
				(type solid)
			)
			(layer "B.CrtYd")
		)
		(fp_line
			(start 0.499 0.25)
			(end 0.499 -0.249)
			(stroke
				(width 0.15)
				(type solid)
			)
			(layer "B.Fab")
		)
		(fp_line
			(start 0.499 -0.249)
			(end -0.5 -0.249)
			(stroke
				(width 0.15)
				(type solid)
			)
			(layer "B.Fab")
		)
		(fp_line
			(start -0.5 0.25)
			(end 0.499 0.25)
			(stroke
				(width 0.15)
				(type solid)
			)
			(layer "B.Fab")
		)
		(fp_line
			(start -0.5 -0.249)
			(end -0.5 0.25)
			(stroke
				(width 0.15)
				(type solid)
			)
			(layer "B.Fab")
		)
		(pad "1" smd roundrect
			(at -0.5 0 90)
			(size 0.6 0.6)
			(layers "B.Cu" "B.Mask" "B.Paste")
			(roundrect_rratio 0.25)
			(net 200 "+3V3")
			(pintype "passive")
		)
		(pad "2" smd roundrect
			(at 0.499 0 180)
			(size 0.6 0.6)
			(layers "B.Cu" "B.Mask" "B.Paste")
			(roundrect_rratio 0.25)
			(net 635 "/FPGA Config/CFGBVS")
			(pintype "passive")
		)
	)
	(footprint "antmicro-footprints:R_0402_1005Metric"
		(layer "B.Cu")
		(at 124.75 187.85 -90)
		(descr "Resistor SMD 0402")
		(tags "resistor SMD 0402")
		(property "Reference" "R22"
			(at 0.85 -0.35 90)
			(layer "B.SilkS")
			(effects
				(font
					(size 0.7 0.7)
					(thickness 0.15)
				)
				(justify left bottom mirror)
			)
		)
		(property "Value" "R_100R_0402"
			(at -1.011843 -1.772047 90)
			(layer "B.Fab")
			(effects
				(font
					(size 0.7 0.7)
					(thickness 0.15)
				)
				(justify left bottom mirror)
			)
		)
		(property "Datasheet" "https://www.bourns.com/docs/product-datasheets/cr.pdf"
			(at 0 0 270)
			(layer "F.Fab")
			(hide yes)
			(effects
				(font
					(size 1.27 1.27)
					(thickness 0.15)
				)
			)
		)
		(property "Author" "Antmicro"
			(at -63.1 312.6 0)
			(layer "B.Fab")
			(hide yes)
			(effects
				(font
					(size 1 1)
					(thickness 0.15)
				)
				(justify mirror)
			)
		)
		(property "License" "Apache-2.0"
			(at -63.1 312.6 0)
			(layer "B.Fab")
			(hide yes)
			(effects
				(font
					(size 1 1)
					(thickness 0.15)
				)
				(justify mirror)
			)
		)
		(property "MPN" "CR0402-FX-1000GLF"
			(at -63.1 312.6 0)
			(layer "B.Fab")
			(hide yes)
			(effects
				(font
					(size 1 1)
					(thickness 0.15)
				)
				(justify mirror)
			)
		)
		(property "Manufacturer" "Bourns"
			(at -63.1 312.6 0)
			(layer "B.Fab")
			(hide yes)
			(effects
				(font
					(size 1 1)
					(thickness 0.15)
				)
				(justify mirror)
			)
		)
		(property "Tolerance" "1%"
			(at -63.1 312.6 0)
			(layer "B.Fab")
			(hide yes)
			(effects
				(font
					(size 1 1)
					(thickness 0.15)
				)
				(justify mirror)
			)
		)
		(property "Val" "100R"
			(at -63.1 312.6 0)
			(layer "B.Fab")
			(hide yes)
			(effects
				(font
					(size 1 1)
					(thickness 0.15)
				)
				(justify mirror)
			)
		)
		(sheetname "/FPGA bank 14/")
		(sheetfile "fpga-bank-14.kicad_sch")
		(attr exclude_from_pos_files exclude_from_bom dnp)
		(fp_rect
			(start -0.93 0.47)
			(end 0.93 -0.47)
			(stroke
				(width 0.05)
				(type solid)
			)
			(fill no)
			(layer "B.CrtYd")
		)
		(fp_rect
			(start -0.5 0.25)
			(end 0.5 -0.25)
			(stroke
				(width 0.15)
				(type solid)
			)
			(fill no)
			(layer "B.Fab")
		)
		(pad "1" smd roundrect
			(at -0.485 0 270)
			(size 0.59 0.64)
			(layers "B.Cu" "B.Mask" "B.Paste")
			(roundrect_rratio 0.25)
			(net 612 "/FPGA bank 14/PUDC_B")
			(pintype "passive")
		)
		(pad "2" smd roundrect
			(at 0.485 0 270)
			(size 0.59 0.64)
			(layers "B.Cu" "B.Mask" "B.Paste")
			(roundrect_rratio 0.25)
			(net 1 "GND")
			(pintype "passive")
		)
	)
	(footprint "antmicro-footprints:R_0402_1005Metric"
		(layer "B.Cu")
		(at 153.775001 175.3 180)
		(descr "Resistor SMD 0402")
		(tags "resistor SMD 0402")
		(property "Reference" "R18"
			(at -1.122484 0.772697 0)
			(layer "B.SilkS")
			(hide yes)
			(effects
				(font
					(size 0.7 0.7)
					(thickness 0.15)
				)
				(justify left bottom mirror)
			)
		)
		(property "Value" "R_4k7_0402"
			(at -1.011843 -1.772047 0)
			(layer "B.Fab")
			(effects
				(font
					(size 0.7 0.7)
					(thickness 0.15)
				)
				(justify left bottom mirror)
			)
		)
		(property "Datasheet" "https://www.bourns.com/docs/product-datasheets/cr.pdf"
			(at 0 0 180)
			(layer "F.Fab")
			(hide yes)
			(effects
				(font
					(size 1.27 1.27)
					(thickness 0.15)
				)
			)
		)
		(property "Author" "Antmicro"
			(at 307.550002 350.6 0)
			(layer "B.Fab")
			(hide yes)
			(effects
				(font
					(size 1 1)
					(thickness 0.15)
				)
				(justify mirror)
			)
		)
		(property "License" "Apache-2.0"
			(at 307.550002 350.6 0)
			(layer "B.Fab")
			(hide yes)
			(effects
				(font
					(size 1 1)
					(thickness 0.15)
				)
				(justify mirror)
			)
		)
		(property "MPN" "CR0402-FX-4701GLF"
			(at 307.550002 350.6 0)
			(layer "B.Fab")
			(hide yes)
			(effects
				(font
					(size 1 1)
					(thickness 0.15)
				)
				(justify mirror)
			)
		)
		(property "Manufacturer" "Bourns"
			(at 307.550002 350.6 0)
			(layer "B.Fab")
			(hide yes)
			(effects
				(font
					(size 1 1)
					(thickness 0.15)
				)
				(justify mirror)
			)
		)
		(property "Tolerance" "1%"
			(at 307.550002 350.6 0)
			(layer "B.Fab")
			(hide yes)
			(effects
				(font
					(size 1 1)
					(thickness 0.15)
				)
				(justify mirror)
			)
		)
		(property "Val" "4k7"
			(at 307.550002 350.6 0)
			(layer "B.Fab")
			(hide yes)
			(effects
				(font
					(size 1 1)
					(thickness 0.15)
				)
				(justify mirror)
			)
		)
		(sheetname "/FPGA Config/")
		(sheetfile "fpga-config.kicad_sch")
		(attr smd)
		(fp_rect
			(start -0.93 0.47)
			(end 0.93 -0.47)
			(stroke
				(width 0.05)
				(type solid)
			)
			(fill no)
			(layer "B.CrtYd")
		)
		(fp_rect
			(start -0.5 0.25)
			(end 0.5 -0.25)
			(stroke
				(width 0.15)
				(type solid)
			)
			(fill no)
			(layer "B.Fab")
		)
		(pad "1" smd roundrect
			(at -0.485 0 180)
			(size 0.59 0.64)
			(layers "B.Cu" "B.Mask" "B.Paste")
			(roundrect_rratio 0.25)
			(net 200 "+3V3")
			(pintype "passive")
		)
		(pad "2" smd roundrect
			(at 0.485 0 180)
			(size 0.59 0.64)
			(layers "B.Cu" "B.Mask" "B.Paste")
			(roundrect_rratio 0.25)
			(net 634 "/FPGA Config/PROGRAM_B")
			(pintype "passive")
		)
	)
)
